(kicad_pcb
	(version 20260206)
	(generator "pcbnew")
	(generator_version "10.0")
	(general
		(thickness 1.6)
		(legacy_teardrops no)
	)
	(paper "A4")
	(title_block
		(title "01162023_DA0F0TEBIF0_F0T_Expander_BD_F_brd_V02_OCP.brd")
		(comment 1 "Grand Teton / footprints 5452-5458 of 9728")
	)
	(layers
		(0 "F.Cu" signal "TOP")
		(4 "In1.Cu" signal "GND")
		(6 "In2.Cu" signal "VCC")
		(8 "In3.Cu" signal "VCC1")
		(10 "In4.Cu" signal "GND1")
		(12 "In5.Cu" signal "IN1")
		(14 "In6.Cu" signal "GND2")
		(16 "In7.Cu" signal "IN2")
		(18 "In8.Cu" signal "GND3")
		(20 "In9.Cu" signal "IN3")
		(22 "In10.Cu" signal "GND4")
		(24 "In11.Cu" signal "IN4")
		(26 "In12.Cu" signal "GND5")
		(28 "In13.Cu" signal "IN5")
		(30 "In14.Cu" signal "GND6")
		(32 "In15.Cu" signal "IN6")
		(34 "In16.Cu" signal "GND7")
		(2 "B.Cu" signal "BOTTOM")
		(9 "F.Adhes" user "F.Adhesive")
		(11 "B.Adhes" user "B.Adhesive")
		(13 "F.Paste" user "Package Geometry/Pastemask Top")
		(15 "B.Paste" user "Package Geometry/Pastemask Bottom")
		(5 "F.SilkS" user "Ref Des/Silkscreen Top")
		(7 "B.SilkS" user "Ref Des/Silkscreen Bottom")
		(1 "F.Mask" user "Board Geometry/Soldermask Top")
		(3 "B.Mask" user "Board Geometry/Soldermask Bottom")
		(17 "Dwgs.User" user "User.Drawings")
		(19 "Cmts.User" user "User.Comments")
		(21 "Eco1.User" user "User.Eco1")
		(23 "Eco2.User" user "User.Eco2")
		(25 "Edge.Cuts" user "Board Geometry/Outline")
		(27 "Margin" user)
		(31 "F.CrtYd" user "Package Geometry/Place Bound Top")
		(29 "B.CrtYd" user "Package Geometry/Place Bound Bottom")
		(35 "F.Fab" user "Ref Des/Assembly Top")
		(33 "B.Fab" user "Ref Des/Assembly Bottom")
	)
	(footprint ""
		(layer "F.Cu")
		(at 412.124652 -158.080202 90)
		(property "Reference" "R2478"
			(at 0 0 90)
			(layer "F.SilkS")
			(hide yes)
			(effects
				(font
					(size 1.27 1.27)
				)
			)
		)
		(property "Value" ""
			(at 0 0 90)
			(layer "F.Fab")
			(effects
				(font
					(size 1.27 1.27)
				)
			)
		)
		(duplicate_pad_numbers_are_jumpers no)
		(fp_line
			(start 0.7874 -0.4064)
			(end 0.7874 0.4064)
			(stroke
				(width 0.1524)
				(type default)
			)
			(layer "F.SilkS")
		)
		(fp_line
			(start -0.7874 -0.4064)
			(end 0.7874 -0.4064)
			(stroke
				(width 0.1524)
				(type default)
			)
			(layer "F.SilkS")
		)
		(fp_line
			(start 0.7874 0.4064)
			(end -0.7874 0.4064)
			(stroke
				(width 0.1524)
				(type default)
			)
			(layer "F.SilkS")
		)
		(fp_line
			(start -0.7874 0.4064)
			(end -0.7874 -0.4064)
			(stroke
				(width 0.1524)
				(type default)
			)
			(layer "F.SilkS")
		)
		(fp_line
			(start -0.12065 -0.305054)
			(end -0.12065 -0.2794)
			(stroke
				(width 0.1)
				(type default)
			)
			(layer "F.Fab")
		)
		(fp_line
			(start -0.67945 -0.305054)
			(end -0.12065 -0.305054)
			(stroke
				(width 0.1)
				(type default)
			)
			(layer "F.Fab")
		)
		(fp_line
			(start 0.67945 -0.3048)
			(end 0.67945 0.3048)
			(stroke
				(width 0.1)
				(type default)
			)
			(layer "F.Fab")
		)
		(fp_line
			(start 0.12065 -0.3048)
			(end 0.67945 -0.3048)
			(stroke
				(width 0.1)
				(type default)
			)
			(layer "F.Fab")
		)
		(fp_line
			(start 0.12065 -0.2794)
			(end 0.12065 -0.3048)
			(stroke
				(width 0.1)
				(type default)
			)
			(layer "F.Fab")
		)
		(fp_line
			(start -0.12065 -0.2794)
			(end 0.12065 -0.2794)
			(stroke
				(width 0.1)
				(type default)
			)
			(layer "F.Fab")
		)
		(fp_line
			(start 0.120396 0.2794)
			(end -0.12065 0.2794)
			(stroke
				(width 0.1)
				(type default)
			)
			(layer "F.Fab")
		)
		(fp_line
			(start -0.12065 0.2794)
			(end -0.12065 0.3048)
			(stroke
				(width 0.1)
				(type default)
			)
			(layer "F.Fab")
		)
		(fp_line
			(start 0.67945 0.3048)
			(end 0.120396 0.3048)
			(stroke
				(width 0.1)
				(type default)
			)
			(layer "F.Fab")
		)
		(fp_line
			(start 0.120396 0.3048)
			(end 0.120396 0.2794)
			(stroke
				(width 0.1)
				(type default)
			)
			(layer "F.Fab")
		)
		(fp_line
			(start -0.12065 0.3048)
			(end -0.67945 0.3048)
			(stroke
				(width 0.1)
				(type default)
			)
			(layer "F.Fab")
		)
		(fp_line
			(start -0.67945 0.3048)
			(end -0.67945 -0.305054)
			(stroke
				(width 0.1)
				(type default)
			)
			(layer "F.Fab")
		)
		(pad "1" smd circle
			(at -0.40005 0 90)
			(size 0 0)
			(layers "F.Cu" "F.Mask" "F.Paste")
			(net "NIC7_PWRBRK_R_N")
		)
		(pad "2" smd circle
			(at 0.40005 0 90)
			(size 0 0)
			(layers "F.Cu" "F.Mask" "F.Paste")
			(net "NIC7_PWRBRK_N")
		)
	)
	(footprint ""
		(layer "F.Cu")
		(at 220.132656 -285.911544 180)
		(property "Reference" "PC238"
			(at 0 0 180)
			(layer "F.SilkS")
			(hide yes)
			(effects
				(font
					(size 1.27 1.27)
				)
			)
		)
		(property "Value" ""
			(at 0 0 180)
			(layer "F.Fab")
			(effects
				(font
					(size 1.27 1.27)
				)
			)
		)
		(duplicate_pad_numbers_are_jumpers no)
		(fp_line
			(start 2.750058 2.750058)
			(end 2.750058 0.9398)
			(stroke
				(width 0.1524)
				(type default)
			)
			(layer "F.SilkS")
		)
		(fp_line
			(start 2.750058 -0.9398)
			(end 2.750058 -2.750058)
			(stroke
				(width 0.1524)
				(type default)
			)
			(layer "F.SilkS")
		)
		(fp_line
			(start 2.750058 -2.750058)
			(end -1.988058 -2.750058)
			(stroke
				(width 0.1524)
				(type default)
			)
			(layer "F.SilkS")
		)
		(fp_line
			(start -1.988058 2.750058)
			(end 2.750058 2.750058)
			(stroke
				(width 0.1524)
				(type default)
			)
			(layer "F.SilkS")
		)
		(fp_line
			(start -1.988058 -2.750058)
			(end -2.750058 -1.988058)
			(stroke
				(width 0.1524)
				(type default)
			)
			(layer "F.SilkS")
		)
		(fp_line
			(start -2.750058 1.988058)
			(end -1.988058 2.750058)
			(stroke
				(width 0.1524)
				(type default)
			)
			(layer "F.SilkS")
		)
		(fp_line
			(start -2.750058 0.9398)
			(end -2.750058 1.988058)
			(stroke
				(width 0.1524)
				(type default)
			)
			(layer "F.SilkS")
		)
		(fp_line
			(start -2.750058 -1.988058)
			(end -2.750058 -0.9398)
			(stroke
				(width 0.1524)
				(type default)
			)
			(layer "F.SilkS")
		)
		(fp_line
			(start 2.750058 2.750058)
			(end 2.750058 -2.750058)
			(stroke
				(width 0.1)
				(type default)
			)
			(layer "F.Fab")
		)
		(fp_line
			(start 2.750058 -2.750058)
			(end -2.750058 -2.750058)
			(stroke
				(width 0.1)
				(type default)
			)
			(layer "F.Fab")
		)
		(fp_line
			(start -2.750058 2.750058)
			(end 2.750058 2.750058)
			(stroke
				(width 0.1)
				(type default)
			)
			(layer "F.Fab")
		)
		(fp_line
			(start -2.750058 -2.750058)
			(end -2.750058 2.750058)
			(stroke
				(width 0.1)
				(type default)
			)
			(layer "F.Fab")
		)
		(pad "1" smd rect
			(at -2.199894 0 270)
			(size 1.6002 3.0226)
			(layers "F.Cu" "F.Mask" "F.Paste")
			(net "P1V25_PEX1_R")
		)
		(pad "2" smd rect
			(at 2.199894 0 270)
			(size 1.6002 3.0226)
			(layers "F.Cu" "F.Mask" "F.Paste")
			(net "GND")
		)
	)
	(footprint ""
		(layer "F.Cu")
		(at 377.657868 -27.006296 -90)
		(property "Reference" "PR7125"
			(at 0 0 270)
			(layer "F.SilkS")
			(hide yes)
			(effects
				(font
					(size 1.27 1.27)
				)
			)
		)
		(property "Value" ""
			(at 0 0 270)
			(layer "F.Fab")
			(effects
				(font
					(size 1.27 1.27)
				)
			)
		)
		(duplicate_pad_numbers_are_jumpers no)
		(fp_line
			(start -0.7874 0.4064)
			(end -0.7874 -0.4064)
			(stroke
				(width 0.1524)
				(type default)
			)
			(layer "F.SilkS")
		)
		(fp_line
			(start 0.7874 0.4064)
			(end -0.7874 0.4064)
			(stroke
				(width 0.1524)
				(type default)
			)
			(layer "F.SilkS")
		)
		(fp_line
			(start -0.7874 -0.4064)
			(end 0.7874 -0.4064)
			(stroke
				(width 0.1524)
				(type default)
			)
			(layer "F.SilkS")
		)
		(fp_line
			(start 0.7874 -0.4064)
			(end 0.7874 0.4064)
			(stroke
				(width 0.1524)
				(type default)
			)
			(layer "F.SilkS")
		)
		(fp_line
			(start -0.67945 0.3048)
			(end -0.67945 -0.305054)
			(stroke
				(width 0.1)
				(type default)
			)
			(layer "F.Fab")
		)
		(fp_line
			(start -0.12065 0.3048)
			(end -0.67945 0.3048)
			(stroke
				(width 0.1)
				(type default)
			)
			(layer "F.Fab")
		)
		(fp_line
			(start 0.120396 0.3048)
			(end 0.120396 0.2794)
			(stroke
				(width 0.1)
				(type default)
			)
			(layer "F.Fab")
		)
		(fp_line
			(start 0.67945 0.3048)
			(end 0.120396 0.3048)
			(stroke
				(width 0.1)
				(type default)
			)
			(layer "F.Fab")
		)
		(fp_line
			(start -0.12065 0.2794)
			(end -0.12065 0.3048)
			(stroke
				(width 0.1)
				(type default)
			)
			(layer "F.Fab")
		)
		(fp_line
			(start 0.120396 0.2794)
			(end -0.12065 0.2794)
			(stroke
				(width 0.1)
				(type default)
			)
			(layer "F.Fab")
		)
		(fp_line
			(start -0.12065 -0.2794)
			(end 0.12065 -0.2794)
			(stroke
				(width 0.1)
				(type default)
			)
			(layer "F.Fab")
		)
		(fp_line
			(start 0.12065 -0.2794)
			(end 0.12065 -0.3048)
			(stroke
				(width 0.1)
				(type default)
			)
			(layer "F.Fab")
		)
		(fp_line
			(start 0.12065 -0.3048)
			(end 0.67945 -0.3048)
			(stroke
				(width 0.1)
				(type default)
			)
			(layer "F.Fab")
		)
		(fp_line
			(start 0.67945 -0.3048)
			(end 0.67945 0.3048)
			(stroke
				(width 0.1)
				(type default)
			)
			(layer "F.Fab")
		)
		(fp_line
			(start -0.67945 -0.305054)
			(end -0.12065 -0.305054)
			(stroke
				(width 0.1)
				(type default)
			)
			(layer "F.Fab")
		)
		(fp_line
			(start -0.12065 -0.305054)
			(end -0.12065 -0.2794)
			(stroke
				(width 0.1)
				(type default)
			)
			(layer "F.Fab")
		)
		(pad "1" smd circle
			(at -0.40005 0 270)
			(size 0 0)
			(layers "F.Cu" "F.Mask" "F.Paste")
			(net "P3V3_SSD13_CO_MODE")
		)
		(pad "2" smd circle
			(at 0.40005 0 270)
			(size 0 0)
			(layers "F.Cu" "F.Mask" "F.Paste")
			(net "GND")
		)
	)
	(footprint ""
		(layer "F.Cu")
		(at 223.586294 -175.50638)
		(property "Reference" "R3146"
			(at 0 0 0)
			(layer "F.SilkS")
			(hide yes)
			(effects
				(font
					(size 1.27 1.27)
				)
			)
		)
		(property "Value" ""
			(at 0 0 0)
			(layer "F.Fab")
			(effects
				(font
					(size 1.27 1.27)
				)
			)
		)
		(duplicate_pad_numbers_are_jumpers no)
		(fp_line
			(start -0.7874 -0.4064)
			(end 0.7874 -0.4064)
			(stroke
				(width 0.1524)
				(type default)
			)
			(layer "F.SilkS")
		)
		(fp_line
			(start -0.7874 0.4064)
			(end -0.7874 -0.4064)
			(stroke
				(width 0.1524)
				(type default)
			)
			(layer "F.SilkS")
		)
		(fp_line
			(start 0.7874 -0.4064)
			(end 0.7874 0.4064)
			(stroke
				(width 0.1524)
				(type default)
			)
			(layer "F.SilkS")
		)
		(fp_line
			(start 0.7874 0.4064)
			(end -0.7874 0.4064)
			(stroke
				(width 0.1524)
				(type default)
			)
			(layer "F.SilkS")
		)
		(fp_line
			(start -0.67945 -0.305054)
			(end -0.12065 -0.305054)
			(stroke
				(width 0.1)
				(type default)
			)
			(layer "F.Fab")
		)
		(fp_line
			(start -0.67945 0.3048)
			(end -0.67945 -0.305054)
			(stroke
				(width 0.1)
				(type default)
			)
			(layer "F.Fab")
		)
		(fp_line
			(start -0.12065 -0.305054)
			(end -0.12065 -0.2794)
			(stroke
				(width 0.1)
				(type default)
			)
			(layer "F.Fab")
		)
		(fp_line
			(start -0.12065 -0.2794)
			(end 0.12065 -0.2794)
			(stroke
				(width 0.1)
				(type default)
			)
			(layer "F.Fab")
		)
		(fp_line
			(start -0.12065 0.2794)
			(end -0.12065 0.3048)
			(stroke
				(width 0.1)
				(type default)
			)
			(layer "F.Fab")
		)
		(fp_line
			(start -0.12065 0.3048)
			(end -0.67945 0.3048)
			(stroke
				(width 0.1)
				(type default)
			)
			(layer "F.Fab")
		)
		(fp_line
			(start 0.120396 0.2794)
			(end -0.12065 0.2794)
			(stroke
				(width 0.1)
				(type default)
			)
			(layer "F.Fab")
		)
		(fp_line
			(start 0.120396 0.3048)
			(end 0.120396 0.2794)
			(stroke
				(width 0.1)
				(type default)
			)
			(layer "F.Fab")
		)
		(fp_line
			(start 0.12065 -0.3048)
			(end 0.67945 -0.3048)
			(stroke
				(width 0.1)
				(type default)
			)
			(layer "F.Fab")
		)
		(fp_line
			(start 0.12065 -0.2794)
			(end 0.12065 -0.3048)
			(stroke
				(width 0.1)
				(type default)
			)
			(layer "F.Fab")
		)
		(fp_line
			(start 0.67945 -0.3048)
			(end 0.67945 0.3048)
			(stroke
				(width 0.1)
				(type default)
			)
			(layer "F.Fab")
		)
		(fp_line
			(start 0.67945 0.3048)
			(end 0.120396 0.3048)
			(stroke
				(width 0.1)
				(type default)
			)
			(layer "F.Fab")
		)
		(pad "1" smd circle
			(at -0.40005 0)
			(size 0 0)
			(layers "F.Cu" "F.Mask" "F.Paste")
			(net "P12V_AUX")
		)
		(pad "2" smd circle
			(at 0.40005 0)
			(size 0 0)
			(layers "F.Cu" "F.Mask" "F.Paste")
			(net "ADM1085_IN")
		)
	)
	(footprint ""
		(layer "F.Cu")
		(at 402.25218 -356.244906 90)
		(property "Reference" "C730"
			(at 0 0 90)
			(layer "F.SilkS")
			(hide yes)
			(effects
				(font
					(size 1.27 1.27)
				)
			)
		)
		(property "Value" ""
			(at 0 0 90)
			(layer "F.Fab")
			(effects
				(font
					(size 1.27 1.27)
				)
			)
		)
		(duplicate_pad_numbers_are_jumpers no)
		(fp_line
			(start 0.299974 -0.150114)
			(end 0.299974 0.150114)
			(stroke
				(width 0.1)
				(type default)
			)
			(layer "F.Fab")
		)
		(fp_line
			(start -0.299974 -0.150114)
			(end 0.299974 -0.150114)
			(stroke
				(width 0.1)
				(type default)
			)
			(layer "F.Fab")
		)
		(fp_line
			(start 0.299974 0.150114)
			(end -0.299974 0.150114)
			(stroke
				(width 0.1)
				(type default)
			)
			(layer "F.Fab")
		)
		(fp_line
			(start -0.299974 0.150114)
			(end -0.299974 -0.150114)
			(stroke
				(width 0.1)
				(type default)
			)
			(layer "F.Fab")
		)
		(pad "1" smd rect
			(at -0.2667 0 90)
			(size 0.3048 0.381)
			(layers "F.Cu" "F.Mask" "F.Paste")
			(net "P5E_PEX3_STN5_TX_DP<95>")
		)
		(pad "2" smd rect
			(at 0.2667 0 90)
			(size 0.3048 0.381)
			(layers "F.Cu" "F.Mask" "F.Paste")
			(net "P5E_PEX3_STN5_TX_C_DP<95>")
		)
	)
	(footprint ""
		(layer "F.Cu")
		(at 265.487658 -298.020232)
		(property "Reference" "C3369"
			(at 0 0 0)
			(layer "F.SilkS")
			(hide yes)
			(effects
				(font
					(size 1.27 1.27)
				)
			)
		)
		(property "Value" ""
			(at 0 0 0)
			(layer "F.Fab")
			(effects
				(font
					(size 1.27 1.27)
				)
			)
		)
		(duplicate_pad_numbers_are_jumpers no)
		(fp_line
			(start -1.2954 -0.5842)
			(end 1.2954 -0.5842)
			(stroke
				(width 0.1524)
				(type default)
			)
			(layer "F.SilkS")
		)
		(fp_line
			(start -1.2954 0.5842)
			(end -1.2954 -0.5842)
			(stroke
				(width 0.1524)
				(type default)
			)
			(layer "F.SilkS")
		)
		(fp_line
			(start 1.2954 -0.5842)
			(end 1.2954 0.5842)
			(stroke
				(width 0.1524)
				(type default)
			)
			(layer "F.SilkS")
		)
		(fp_line
			(start 1.2954 0.5842)
			(end -1.2954 0.5842)
			(stroke
				(width 0.1524)
				(type default)
			)
			(layer "F.SilkS")
		)
		(fp_line
			(start -1.1938 -0.4064)
			(end -0.8636 -0.4064)
			(stroke
				(width 0.1)
				(type default)
			)
			(layer "F.Fab")
		)
		(fp_line
			(start -1.1938 0.4064)
			(end -1.1938 -0.4064)
			(stroke
				(width 0.1)
				(type default)
			)
			(layer "F.Fab")
		)
		(fp_line
			(start -0.8636 -0.4572)
			(end 0.8636 -0.4572)
			(stroke
				(width 0.1)
				(type default)
			)
			(layer "F.Fab")
		)
		(fp_line
			(start -0.8636 -0.4064)
			(end -0.8636 -0.4572)
			(stroke
				(width 0.1)
				(type default)
			)
			(layer "F.Fab")
		)
		(fp_line
			(start -0.8636 0.4064)
			(end -1.1938 0.4064)
			(stroke
				(width 0.1)
				(type default)
			)
			(layer "F.Fab")
		)
		(fp_line
			(start -0.8636 0.4572)
			(end -0.8636 0.4064)
			(stroke
				(width 0.1)
				(type default)
			)
			(layer "F.Fab")
		)
		(fp_line
			(start 0.8636 -0.4572)
			(end 0.8636 -0.4064)
			(stroke
				(width 0.1)
				(type default)
			)
			(layer "F.Fab")
		)
		(fp_line
			(start 0.8636 -0.4064)
			(end 1.1938 -0.4064)
			(stroke
				(width 0.1)
				(type default)
			)
			(layer "F.Fab")
		)
		(fp_line
			(start 0.8636 0.4064)
			(end 0.8636 0.4572)
			(stroke
				(width 0.1)
				(type default)
			)
			(layer "F.Fab")
		)
		(fp_line
			(start 0.8636 0.4572)
			(end -0.8636 0.4572)
			(stroke
				(width 0.1)
				(type default)
			)
			(layer "F.Fab")
		)
		(fp_line
			(start 1.1938 -0.4064)
			(end 1.1938 0.4064)
			(stroke
				(width 0.1)
				(type default)
			)
			(layer "F.Fab")
		)
		(fp_line
			(start 1.1938 0.4064)
			(end 0.8636 0.4064)
			(stroke
				(width 0.1)
				(type default)
			)
			(layer "F.Fab")
		)
		(pad "1" smd rect
			(at -0.7366 0 270)
			(size 0.7112 0.8128)
			(layers "F.Cu" "F.Mask" "F.Paste")
			(net "PCEPLL0_VDDA18_PEX2")
		)
		(pad "2" smd rect
			(at 0.7366 0 270)
			(size 0.7112 0.8128)
			(layers "F.Cu" "F.Mask" "F.Paste")
			(net "GND")
		)
	)
	(footprint ""
		(layer "F.Cu")
		(at 333.974186 -10.534142 -90)
		(property "Reference" "R1708"
			(at 0 0 270)
			(layer "F.SilkS")
			(hide yes)
			(effects
				(font
					(size 1.27 1.27)
				)
			)
		)
		(property "Value" ""
			(at 0 0 270)
			(layer "F.Fab")
			(effects
				(font
					(size 1.27 1.27)
				)
			)
		)
		(duplicate_pad_numbers_are_jumpers no)
		(fp_line
			(start -0.7874 0.4064)
			(end -0.7874 -0.4064)
			(stroke
				(width 0.1524)
				(type default)
			)
			(layer "F.SilkS")
		)
		(fp_line
			(start 0.7874 0.4064)
			(end -0.7874 0.4064)
			(stroke
				(width 0.1524)
				(type default)
			)
			(layer "F.SilkS")
		)
		(fp_line
			(start -0.7874 -0.4064)
			(end 0.7874 -0.4064)
			(stroke
				(width 0.1524)
				(type default)
			)
			(layer "F.SilkS")
		)
		(fp_line
			(start 0.7874 -0.4064)
			(end 0.7874 0.4064)
			(stroke
				(width 0.1524)
				(type default)
			)
			(layer "F.SilkS")
		)
		(fp_line
			(start -0.67945 0.3048)
			(end -0.67945 -0.305054)
			(stroke
				(width 0.1)
				(type default)
			)
			(layer "F.Fab")
		)
		(fp_line
			(start -0.12065 0.3048)
			(end -0.67945 0.3048)
			(stroke
				(width 0.1)
				(type default)
			)
			(layer "F.Fab")
		)
		(fp_line
			(start 0.120396 0.3048)
			(end 0.120396 0.2794)
			(stroke
				(width 0.1)
				(type default)
			)
			(layer "F.Fab")
		)
		(fp_line
			(start 0.67945 0.3048)
			(end 0.120396 0.3048)
			(stroke
				(width 0.1)
				(type default)
			)
			(layer "F.Fab")
		)
		(fp_line
			(start -0.12065 0.2794)
			(end -0.12065 0.3048)
			(stroke
				(width 0.1)
				(type default)
			)
			(layer "F.Fab")
		)
		(fp_line
			(start 0.120396 0.2794)
			(end -0.12065 0.2794)
			(stroke
				(width 0.1)
				(type default)
			)
			(layer "F.Fab")
		)
		(fp_line
			(start -0.12065 -0.2794)
			(end 0.12065 -0.2794)
			(stroke
				(width 0.1)
				(type default)
			)
			(layer "F.Fab")
		)
		(fp_line
			(start 0.12065 -0.2794)
			(end 0.12065 -0.3048)
			(stroke
				(width 0.1)
				(type default)
			)
			(layer "F.Fab")
		)
		(fp_line
			(start 0.12065 -0.3048)
			(end 0.67945 -0.3048)
			(stroke
				(width 0.1)
				(type default)
			)
			(layer "F.Fab")
		)
		(fp_line
			(start 0.67945 -0.3048)
			(end 0.67945 0.3048)
			(stroke
				(width 0.1)
				(type default)
			)
			(layer "F.Fab")
		)
		(fp_line
			(start -0.67945 -0.305054)
			(end -0.12065 -0.305054)
			(stroke
				(width 0.1)
				(type default)
			)
			(layer "F.Fab")
		)
		(fp_line
			(start -0.12065 -0.305054)
			(end -0.12065 -0.2794)
			(stroke
				(width 0.1)
				(type default)
			)
			(layer "F.Fab")
		)
		(pad "1" smd circle
			(at -0.40005 0 270)
			(size 0 0)
			(layers "F.Cu" "F.Mask" "F.Paste")
			(net "SMB_ISO_SSD11_R_SCL")
		)
		(pad "2" smd circle
			(at 0.40005 0 270)
			(size 0 0)
			(layers "F.Cu" "F.Mask" "F.Paste")
			(net "SMB_ISO_SSD11_SCL")
		)
	)
)
